# BASEBOARD_FAB2 (Tioga Pass) — schematic netlist excerpt (pin names and nets, part order shuffled) for the footprints in the layout excerpt that follows; sources: Cadence DE-HDL packaged netlist, KiCad conversion of Wiwynn_Tioga_Pass_MB.brd

J6M1  SCONN288_H44441003  SCONN  pkg PIP  page 50
  \12v\(1)  = P12V_NVDIMM_DEF
  VSS(93)  = GND
  DQ(4)  = M_D_DQ<4>
  VSS(92)  = GND
  DQ(0)  = M_D_DQ<0>
  VSS(91)  = GND
  DQS9P  = M_D_DQS_DP<9>
  DQS9N  = M_D_DQS_DN<9>
  VSS(90)  = GND
  DQ(6)  = M_D_DQ<6>
  VSS(89)  = GND
  DQ(2)  = M_D_DQ<2>
  VSS(88)  = GND
  DQ(12)  = M_D_DQ<12>
  VSS(87)  = GND
  DQ(8)  = M_D_DQ<8>
  VSS(86)  = GND
  DQS10P  = M_D_DQS_DP<10>
  DQS10N  = M_D_DQS_DN<10>
  VSS(85)  = GND
  DQ(14)  = M_D_DQ<14>
  VSS(84)  = GND
  DQ(10)  = M_D_DQ<10>
  VSS(83)  = GND
  DQ(20)  = M_D_DQ<20>
  VSS(82)  = GND
  DQ(16)  = M_D_DQ<16>
  VSS(81)  = GND
  DQS11P  = M_D_DQS_DP<11>
  DQS11N  = M_D_DQS_DN<11>
  VSS(80)  = GND
  DQ(22)  = M_D_DQ<22>
  VSS(79)  = GND
  DQ(18)  = M_D_DQ<18>
  VSS(78)  = GND
  DQ(28)  = M_D_DQ<28>
  VSS(77)  = GND
  DQ(24)  = M_D_DQ<24>
  VSS(76)  = GND
  DQS12P  = M_D_DQS_DP<12>
  DQS12N  = M_D_DQS_DN<12>
  VSS(75)  = GND
  DQ(30)  = M_D_DQ<30>
  VSS(74)  = GND
  DQ(26)  = M_D_DQ<26>
  VSS(73)  = GND
  CB(4)  = M_D_ECC<4>
  VSS(72)  = GND
  CB(0)  = M_D_ECC<0>
  VSS(71)  = GND
  DQS17P  = M_D_DQS_DP<17>
  DQS17N  = M_D_DQS_DN<17>
  VSS(70)  = GND
  CB(6)  = M_D_ECC<6>
  VSS(69)  = GND
  CB(2)  = M_D_ECC<2>
  VSS(68)  = GND
  RESET_N  = M_DEF_RST_N
  VDD(25)  = PVDDQ_DEF
  CKE(0)  = M_D_CKE<2>
  VDD(24)  = PVDDQ_DEF
  ACT_N  = M_D_ACT_N
  BG(0)  = M_D_BG<0>
  VDD(23)  = PVDDQ_DEF
  A12  = M_D_MA<12>
  A9  = M_D_MA<9>
  VDD(22)  = PVDDQ_DEF
  A8  = M_D_MA<8>
  A6  = M_D_MA<6>
  VDD(21)  = PVDDQ_DEF
  A3  = M_D_MA<3>
  A1  = M_D_MA<1>
  VDD(20)  = PVDDQ_DEF
  CK0P  = M_D_CLK_DP<2>
  CK0N  = M_D_CLK_DN<2>
  VDD(19)  = PVDDQ_DEF
  VTT(1)  = PVTT_DEF
  EVENT_N  = FM_DIMM_EVENT_COD_N
  A0  = M_D_MA<0>
  VDD(18)  = PVDDQ_DEF
  BA(0)  = M_D_BA<0>
  A16_RAS_N  = M_D_MA<16>
  VDD(17)  = PVDDQ_DEF
  S0_N  = M_D_CS_N<4>
  VDD(16)  = PVDDQ_DEF
  A15_CAS_N  = M_D_MA<15>
  ODT(0)  = M_D_ODT<2>
  VDD(15)  = PVDDQ_DEF
  S1_N  = M_D_CS_N<5>
  VDD(14)  = PVDDQ_DEF
  ODT(1)  = M_D_ODT<3>
  VDD(13)  = PVDDQ_DEF
  S2_N_C(0)  = M_D_CS_N<6>
  VSS(67)  = GND
  DQ(36)  = M_D_DQ<36>
  VSS(66)  = GND
  DQ(32)  = M_D_DQ<32>
  VSS(65)  = GND
  DQS13P  = M_D_DQS_DP<13>
  DQS13N  = M_D_DQS_DN<13>
  VSS(64)  = GND
  DQ(38)  = M_D_DQ<38>
  VSS(63)  = GND
  DQ(34)  = M_D_DQ<34>
  VSS(62)  = GND
  DQ(44)  = M_D_DQ<44>
  VSS(61)  = GND
  DQ(40)  = M_D_DQ<40>
  VSS(60)  = GND
  DQS14P  = M_D_DQS_DP<14>
  DQS14N  = M_D_DQS_DN<14>
  VSS(59)  = GND
  DQ(46)  = M_D_DQ<46>
  VSS(58)  = GND
  DQ(42)  = M_D_DQ<42>
  VSS(57)  = GND
  DQ(52)  = M_D_DQ<52>
  VSS(56)  = GND
  DQ(48)  = M_D_DQ<48>
  VSS(55)  = GND
  DQS15P  = M_D_DQS_DP<15>
  DQS15N  = M_D_DQS_DN<15>
  VSS(54)  = GND
  DQ(54)  = M_D_DQ<54>
  VSS(53)  = GND
  DQ(50)  = M_D_DQ<50>
  VSS(52)  = GND
  DQ(60)  = M_D_DQ<60>
  VSS(51)  = GND
  DQ(56)  = M_D_DQ<56>
  VSS(50)  = GND
  DQS16P  = M_D_DQS_DP<16>
  DQS16N  = M_D_DQS_DN<16>
  VSS(49)  = GND
  DQ(62)  = M_D_DQ<62>
  VSS(48)  = GND
  DQ(58)  = M_D_DQ<58>
  VSS(47)  = GND
  SA(0)  = PVPP_DEF
  SA(1)  = GND
  SCL  = SMB_DDR_DEF_VPP_SCL
  VPP(4)  = PVPP_DEF
  VPP(3)  = PVPP_DEF
  RFU(2)  = TP_CH_D_DIMM_D1_RFU_2
  \12v\(0)  = P12V_NVDIMM_DEF
  VREFCA  = M_D_VREF
  VSS(46)  = GND
  DQ(5)  = M_D_DQ<5>
  VSS(45)  = GND
  DQ(1)  = M_D_DQ<1>
  VSS(44)  = GND
  DQS0N  = M_D_DQS_DN<0>
  DQS0P  = M_D_DQS_DP<0>
  VSS(43)  = GND
  DQ(7)  = M_D_DQ<7>
  VSS(42)  = GND
  DQ(3)  = M_D_DQ<3>
  VSS(41)  = GND
  DQ(13)  = M_D_DQ<13>
  VSS(40)  = GND
  DQ(9)  = M_D_DQ<9>
  VSS(39)  = GND
  DQS1N  = M_D_DQS_DN<1>
  DQS1P  = M_D_DQS_DP<1>
  VSS(38)  = GND
  DQ(15)  = M_D_DQ<15>
  VSS(37)  = GND
  DQ(11)  = M_D_DQ<11>
  VSS(36)  = GND
  DQ(21)  = M_D_DQ<21>
  VSS(35)  = GND
  DQ(17)  = M_D_DQ<17>
  VSS(34)  = GND
  DQS2N  = M_D_DQS_DN<2>
  DQS2P  = M_D_DQS_DP<2>
  VSS(33)  = GND
  DQ(23)  = M_D_DQ<23>
  VSS(32)  = GND
  DQ(19)  = M_D_DQ<19>
  VSS(31)  = GND
  DQ(29)  = M_D_DQ<29>
  VSS(30)  = GND
  DQ(25)  = M_D_DQ<25>
  VSS(29)  = GND
  DQS3N  = M_D_DQS_DN<3>
  DQS3P  = M_D_DQS_DP<3>
  VSS(28)  = GND
  DQ(31)  = M_D_DQ<31>
  VSS(27)  = GND
  DQ(27)  = M_D_DQ<27>
  VSS(26)  = GND
  CB(5)  = M_D_ECC<5>
  VSS(25)  = GND
  CB(1)  = M_D_ECC<1>
  VSS(24)  = GND
  DQS8N  = M_D_DQS_DN<8>
  DQS8P  = M_D_DQS_DP<8>
  VSS(23)  = GND
  CB(7)  = M_D_ECC<7>
  VSS(22)  = GND
  CB(3)  = M_D_ECC<3>
  VSS(21)  = GND
  CKE(1)  = M_D_CKE<3>
  VDD(12)  = PVDDQ_DEF
  RFU(0)  = TP_CH_D_DIMM_D1_RFU_0
  VDD(11)  = PVDDQ_DEF
  BG(1)  = M_D_BG<1>
  ALERT_N  = M_D_ALERT_N
  VDD(10)  = PVDDQ_DEF
  A11  = M_D_MA<11>
  A7  = M_D_MA<7>
  VDD(9)  = PVDDQ_DEF
  A5  = M_D_MA<5>
  A4  = M_D_MA<4>
  VDD(8)  = PVDDQ_DEF
  A2  = M_D_MA<2>
  VDD(7)  = PVDDQ_DEF
  CK1P  = M_D_CLK_DP<3>
  CK1N  = M_D_CLK_DN<3>
  VDD(6)  = PVDDQ_DEF
  VTT(0)  = PVTT_DEF
  PAR  = M_D_PAR
  VDD(5)  = PVDDQ_DEF
  BA(1)  = M_D_BA<1>
  A10  = M_D_MA<10>
  VDD(4)  = PVDDQ_DEF
  RFU(1)  = TP_CH_D_DIMM_D1_RFU_1
  A14_WE_N  = M_D_MA<14>
  VDD(3)  = PVDDQ_DEF
  SAVE_N_NC  = FM_ADR_COMPLETE_DEF_N
  VDD(2)  = PVDDQ_DEF
  A13  = M_D_MA<13>
  VDD(1)  = PVDDQ_DEF
  A17  = M_D_MA<17>
  C(2)  = M_D_C<2>
  VDD(0)  = PVDDQ_DEF
  S3_N_C(1)  = M_D_CS_N<7>
  SA(2)  = GND
  VSS(20)  = GND
  DQ(37)  = M_D_DQ<37>
  VSS(19)  = GND
  DQ(33)  = M_D_DQ<33>
  VSS(18)  = GND
  DQS4N  = M_D_DQS_DN<4>
  DQS4P  = M_D_DQS_DP<4>
  VSS(17)  = GND
  DQ(39)  = M_D_DQ<39>
  VSS(16)  = GND
  DQ(35)  = M_D_DQ<35>
  VSS(15)  = GND
  DQ(45)  = M_D_DQ<45>
  VSS(14)  = GND
  DQ(41)  = M_D_DQ<41>
  VSS(13)  = GND
  DQS5N  = M_D_DQS_DN<5>
  DQS5P  = M_D_DQS_DP<5>
  VSS(12)  = GND
  DQ(47)  = M_D_DQ<47>
  VSS(11)  = GND
  DQ(43)  = M_D_DQ<43>
  VSS(10)  = GND
  DQ(53)  = M_D_DQ<53>
  VSS(9)  = GND
  DQ(49)  = M_D_DQ<49>
  VSS(8)  = GND
  DQS6N  = M_D_DQS_DN<6>
  DQS6P  = M_D_DQS_DP<6>
  VSS(7)  = GND
  DQ(55)  = M_D_DQ<55>
  VSS(6)  = GND
  DQ(51)  = M_D_DQ<51>
  VSS(5)  = GND
  DQ(61)  = M_D_DQ<61>
  VSS(4)  = GND
  DQ(57)  = M_D_DQ<57>
  VSS(3)  = GND
  DQS7N  = M_D_DQS_DN<7>
  DQS7P  = M_D_DQS_DP<7>
  VSS(2)  = GND
  DQ(63)  = M_D_DQ<63>
  VSS(1)  = GND
  DQ(59)  = M_D_DQ<59>
  VSS(0)  = GND
  VDDSPD  = PVPP_DEF
  SDA  = SMB_DDR_DEF_VPP_SDA
  VPP(1)  = PVPP_DEF
  VPP(0)  = PVPP_DEF
  VPP(2)  = PVPP_DEF

(kicad_pcb
	(version 20260206)
	(generator "pcbnew")
	(generator_version "10.0")
	(general
		(thickness 1.6)
		(legacy_teardrops no)
	)
	(paper "A4")
	(title_block
		(title "Wiwynn_Tioga_Pass_MB.brd")
		(comment 1 "Tioga Pass / footprint 3254 of 4770 (J6M1), pads 51-100 of 291")
	)
	(layers
		(0 "F.Cu" signal "TOP")
		(4 "In1.Cu" signal "L2GND")
		(6 "In2.Cu" signal "L3")
		(8 "In3.Cu" signal "L4GND")
		(10 "In4.Cu" signal "L5")
		(12 "In5.Cu" signal "L6GND")
		(14 "In6.Cu" signal "L7VCC")
		(16 "In7.Cu" signal "L8VCC")
		(18 "In8.Cu" signal "L9GND")
		(20 "In9.Cu" signal "L10")
		(22 "In10.Cu" signal "L11GND")
		(24 "In11.Cu" signal "L12")
		(26 "In12.Cu" signal "L13GND")
		(2 "B.Cu" signal "BOTTOM")
		(9 "F.Adhes" user "F.Adhesive")
		(11 "B.Adhes" user "B.Adhesive")
		(13 "F.Paste" user "Package Geometry/Pastemask Top")
		(15 "B.Paste" user "Package Geometry/Pastemask Bottom")
		(5 "F.SilkS" user "Ref Des/Silkscreen Top")
		(7 "B.SilkS" user "Ref Des/Silkscreen Bottom")
		(1 "F.Mask" user "Board Geometry/Soldermask Top")
		(3 "B.Mask" user "Board Geometry/Soldermask Bottom")
		(17 "Dwgs.User" user "User.Drawings")
		(19 "Cmts.User" user "User.Comments")
		(21 "Eco1.User" user "User.Eco1")
		(23 "Eco2.User" user "User.Eco2")
		(25 "Edge.Cuts" user "Board Geometry/Outline")
		(27 "Margin" user)
		(31 "F.CrtYd" user "Package Geometry/Place Bound Top")
		(29 "B.CrtYd" user "Package Geometry/Place Bound Bottom")
		(35 "F.Fab" user "Ref Des/Assembly Top")
		(33 "B.Fab" user "Ref Des/Assembly Bottom")
	)
	(footprint ""
		(layer "B.Cu")
		(at 194.700398 -132.876036 90)
		(property "Reference" "J6M1"
			(at 2.352548 37.96411 0)
			(unlocked yes)
			(layer "B.SilkS")
			(effects
				(font
					(size 0.7874 0.5842)
					(thickness 0.1524)
				)
				(justify left mirror)
			)
		)
		(property "Value" ""
			(at 0 0 90)
			(layer "B.Fab")
			(effects
				(font
					(size 1.27 1.27)
				)
				(justify mirror)
			)
		)
		(duplicate_pad_numbers_are_jumpers no)
		(pad "48" smd rect
			(at 0 39.949882 270)
			(size 1.8034 0.508)
			(layers "B.Cu" "B.Mask" "B.Paste")
			(net "GND")
		)
		(pad "49" smd rect
			(at 0 40.80002 270)
			(size 1.8034 0.508)
			(layers "B.Cu" "B.Mask" "B.Paste")
			(net "M_D_ECC<0>")
		)
		(pad "50" smd rect
			(at 0 41.649904 270)
			(size 1.8034 0.508)
			(layers "B.Cu" "B.Mask" "B.Paste")
			(net "GND")
		)
		(pad "51" smd rect
			(at 0 42.500042 270)
			(size 1.8034 0.508)
			(layers "B.Cu" "B.Mask" "B.Paste")
			(net "M_D_DQS_DP<17>")
		)
		(pad "52" smd rect
			(at 0 43.349926 270)
			(size 1.8034 0.508)
			(layers "B.Cu" "B.Mask" "B.Paste")
			(net "M_D_DQS_DN<17>")
		)
		(pad "53" smd rect
			(at 0 44.200064 270)
			(size 1.8034 0.508)
			(layers "B.Cu" "B.Mask" "B.Paste")
			(net "GND")
		)
		(pad "54" smd rect
			(at 0 45.049948 270)
			(size 1.8034 0.508)
			(layers "B.Cu" "B.Mask" "B.Paste")
			(net "M_D_ECC<6>")
		)
		(pad "55" smd rect
			(at 0 45.900086 270)
			(size 1.8034 0.508)
			(layers "B.Cu" "B.Mask" "B.Paste")
			(net "GND")
		)
		(pad "56" smd rect
			(at 0 46.74997 270)
			(size 1.8034 0.508)
			(layers "B.Cu" "B.Mask" "B.Paste")
			(net "M_D_ECC<2>")
		)
		(pad "57" smd rect
			(at 0 47.600108 270)
			(size 1.8034 0.508)
			(layers "B.Cu" "B.Mask" "B.Paste")
			(net "GND")
		)
		(pad "58" smd rect
			(at 0 48.449992 270)
			(size 1.8034 0.508)
			(layers "B.Cu" "B.Mask" "B.Paste")
			(net "M_DEF_RST_N")
		)
		(pad "59" smd rect
			(at 0 49.299876 270)
			(size 1.8034 0.508)
			(layers "B.Cu" "B.Mask" "B.Paste")
			(net "PVDDQ_DEF")
		)
		(pad "60" smd rect
			(at 0 50.150014 270)
			(size 1.8034 0.508)
			(layers "B.Cu" "B.Mask" "B.Paste")
			(net "M_D_CKE<2>")
		)
		(pad "61" smd rect
			(at 0 50.999898 270)
			(size 1.8034 0.508)
			(layers "B.Cu" "B.Mask" "B.Paste")
			(net "PVDDQ_DEF")
		)
		(pad "62" smd rect
			(at 0 51.850036 270)
			(size 1.8034 0.508)
			(layers "B.Cu" "B.Mask" "B.Paste")
			(net "M_D_ACT_N")
		)
		(pad "63" smd rect
			(at 0 52.69992 270)
			(size 1.8034 0.508)
			(layers "B.Cu" "B.Mask" "B.Paste")
			(net "M_D_BG<0>")
		)
		(pad "64" smd rect
			(at 0 53.550058 270)
			(size 1.8034 0.508)
			(layers "B.Cu" "B.Mask" "B.Paste")
			(net "PVDDQ_DEF")
		)
		(pad "65" smd rect
			(at 0 54.399942 270)
			(size 1.8034 0.508)
			(layers "B.Cu" "B.Mask" "B.Paste")
			(net "M_D_MA<12>")
		)
		(pad "66" smd rect
			(at 0 55.25008 270)
			(size 1.8034 0.508)
			(layers "B.Cu" "B.Mask" "B.Paste")
			(net "M_D_MA<9>")
		)
		(pad "67" smd rect
			(at 0 56.099964 270)
			(size 1.8034 0.508)
			(layers "B.Cu" "B.Mask" "B.Paste")
			(net "PVDDQ_DEF")
		)
		(pad "68" smd rect
			(at 0 56.950102 270)
			(size 1.8034 0.508)
			(layers "B.Cu" "B.Mask" "B.Paste")
			(net "M_D_MA<8>")
		)
		(pad "69" smd rect
			(at 0 57.799986 270)
			(size 1.8034 0.508)
			(layers "B.Cu" "B.Mask" "B.Paste")
			(net "M_D_MA<6>")
		)
		(pad "70" smd rect
			(at 0 58.650124 270)
			(size 1.8034 0.508)
			(layers "B.Cu" "B.Mask" "B.Paste")
			(net "PVDDQ_DEF")
		)
		(pad "71" smd rect
			(at 0 59.500008 270)
			(size 1.8034 0.508)
			(layers "B.Cu" "B.Mask" "B.Paste")
			(net "M_D_MA<3>")
		)
		(pad "72" smd rect
			(at 0 60.349892 270)
			(size 1.8034 0.508)
			(layers "B.Cu" "B.Mask" "B.Paste")
			(net "M_D_MA<1>")
		)
		(pad "73" smd rect
			(at 0 61.20003 270)
			(size 1.8034 0.508)
			(layers "B.Cu" "B.Mask" "B.Paste")
			(net "PVDDQ_DEF")
		)
		(pad "74" smd rect
			(at 0 62.049914 270)
			(size 1.8034 0.508)
			(layers "B.Cu" "B.Mask" "B.Paste")
			(net "M_D_CLK_DP<2>")
		)
		(pad "75" smd rect
			(at 0 62.900052 270)
			(size 1.8034 0.508)
			(layers "B.Cu" "B.Mask" "B.Paste")
			(net "M_D_CLK_DN<2>")
		)
		(pad "76" smd rect
			(at 0 63.749936 270)
			(size 1.8034 0.508)
			(layers "B.Cu" "B.Mask" "B.Paste")
			(net "PVDDQ_DEF")
		)
		(pad "77" smd rect
			(at 0 64.600074 270)
			(size 1.8034 0.508)
			(layers "B.Cu" "B.Mask" "B.Paste")
			(net "PVTT_DEF")
		)
		(pad "78" smd rect
			(at 0 70.550024 270)
			(size 1.8034 0.508)
			(layers "B.Cu" "B.Mask" "B.Paste")
			(net "FM_DIMM_EVENT_COD_N")
		)
		(pad "79" smd rect
			(at 0 71.399908 270)
			(size 1.8034 0.508)
			(layers "B.Cu" "B.Mask" "B.Paste")
			(net "M_D_MA<0>")
		)
		(pad "80" smd rect
			(at 0 72.250046 270)
			(size 1.8034 0.508)
			(layers "B.Cu" "B.Mask" "B.Paste")
			(net "PVDDQ_DEF")
		)
		(pad "81" smd rect
			(at 0 73.09993 270)
			(size 1.8034 0.508)
			(layers "B.Cu" "B.Mask" "B.Paste")
			(net "M_D_BA<0>")
		)
		(pad "82" smd rect
			(at 0 73.950068 270)
			(size 1.8034 0.508)
			(layers "B.Cu" "B.Mask" "B.Paste")
			(net "M_D_MA<16>")
		)
		(pad "83" smd rect
			(at 0 74.799952 270)
			(size 1.8034 0.508)
			(layers "B.Cu" "B.Mask" "B.Paste")
			(net "PVDDQ_DEF")
		)
		(pad "84" smd rect
			(at 0 75.65009 270)
			(size 1.8034 0.508)
			(layers "B.Cu" "B.Mask" "B.Paste")
			(net "M_D_CS_N<4>")
		)
		(pad "85" smd rect
			(at 0 76.499974 270)
			(size 1.8034 0.508)
			(layers "B.Cu" "B.Mask" "B.Paste")
			(net "PVDDQ_DEF")
		)
		(pad "86" smd rect
			(at 0 77.350112 270)
			(size 1.8034 0.508)
			(layers "B.Cu" "B.Mask" "B.Paste")
			(net "M_D_MA<15>")
		)
		(pad "87" smd rect
			(at 0 78.199996 270)
			(size 1.8034 0.508)
			(layers "B.Cu" "B.Mask" "B.Paste")
			(net "M_D_ODT<2>")
		)
		(pad "88" smd rect
			(at 0 79.04988 270)
			(size 1.8034 0.508)
			(layers "B.Cu" "B.Mask" "B.Paste")
			(net "PVDDQ_DEF")
		)
		(pad "89" smd rect
			(at 0 79.900018 270)
			(size 1.8034 0.508)
			(layers "B.Cu" "B.Mask" "B.Paste")
			(net "M_D_CS_N<5>")
		)
		(pad "90" smd rect
			(at 0 80.749902 270)
			(size 1.8034 0.508)
			(layers "B.Cu" "B.Mask" "B.Paste")
			(net "PVDDQ_DEF")
		)
		(pad "91" smd rect
			(at 0 81.60004 270)
			(size 1.8034 0.508)
			(layers "B.Cu" "B.Mask" "B.Paste")
			(net "M_D_ODT<3>")
		)
		(pad "92" smd rect
			(at 0 82.449924 270)
			(size 1.8034 0.508)
			(layers "B.Cu" "B.Mask" "B.Paste")
			(net "PVDDQ_DEF")
		)
		(pad "93" smd rect
			(at 0 83.300062 270)
			(size 1.8034 0.508)
			(layers "B.Cu" "B.Mask" "B.Paste")
			(net "M_D_CS_N<6>")
		)
		(pad "94" smd rect
			(at 0 84.149946 270)
			(size 1.8034 0.508)
			(layers "B.Cu" "B.Mask" "B.Paste")
			(net "GND")
		)
		(pad "95" smd rect
			(at 0 85.000084 270)
			(size 1.8034 0.508)
			(layers "B.Cu" "B.Mask" "B.Paste")
			(net "M_D_DQ<36>")
		)
		(pad "96" smd rect
			(at 0 85.849968 270)
			(size 1.8034 0.508)
			(layers "B.Cu" "B.Mask" "B.Paste")
			(net "GND")
		)
		(pad "97" smd rect
			(at 0 86.700106 270)
			(size 1.8034 0.508)
			(layers "B.Cu" "B.Mask" "B.Paste")
			(net "M_D_DQ<32>")
		)
	)
)
